# T6G (Grand Teton) — schematic netlist excerpt (pin names and nets, part order shuffled) for the footprints in the layout excerpt that follows; sources: Cadence DE-HDL packaged netlist, KiCad conversion of 04192023_DAF0TMB3IC0_F0TG_MB_C_brd_V02_OCP.brd

C2493  Q_CAP  22UF 4V 20% X6S  pkg C0402  page 74 : A = PVDDIO_P1 ; B = GND
C2307  Q_CAP  22UF 4V 20% X6S  pkg C0402  page 73 : A = PVDDCR_CPU0_P1 ; B = GND

(kicad_pcb
	(version 20260206)
	(generator "pcbnew")
	(generator_version "10.0")
	(general
		(thickness 1.6)
		(legacy_teardrops no)
	)
	(paper "A4")
	(title_block
		(title "04192023_DAF0TMB3IC0_F0TG_MB_C_brd_V02_OCP.brd")
		(comment 1 "Grand Teton / footprints 5151-5152 of 8354")
	)
	(layers
		(0 "F.Cu" signal "TOP")
		(4 "In1.Cu" signal "GND")
		(6 "In2.Cu" signal "IN1")
		(8 "In3.Cu" signal "GND1")
		(10 "In4.Cu" signal "IN2")
		(12 "In5.Cu" signal "GND2")
		(14 "In6.Cu" signal "IN3")
		(16 "In7.Cu" signal "GND3")
		(18 "In8.Cu" signal "VCC")
		(20 "In9.Cu" signal "VCC1")
		(22 "In10.Cu" signal "GND4")
		(24 "In11.Cu" signal "IN4")
		(26 "In12.Cu" signal "GND5")
		(28 "In13.Cu" signal "IN5")
		(30 "In14.Cu" signal "GND6")
		(32 "In15.Cu" signal "IN6")
		(34 "In16.Cu" signal "GND7")
		(2 "B.Cu" signal "BOTTOM")
		(9 "F.Adhes" user "F.Adhesive")
		(11 "B.Adhes" user "B.Adhesive")
		(13 "F.Paste" user "Package Geometry/Pastemask Top")
		(15 "B.Paste" user "Package Geometry/Pastemask Bottom")
		(5 "F.SilkS" user "Ref Des/Silkscreen Top")
		(7 "B.SilkS" user "Ref Des/Silkscreen Bottom")
		(1 "F.Mask" user "Board Geometry/Soldermask Top")
		(3 "B.Mask" user "Board Geometry/Soldermask Bottom")
		(17 "Dwgs.User" user "User.Drawings")
		(19 "Cmts.User" user "User.Comments")
		(21 "Eco1.User" user "User.Eco1")
		(23 "Eco2.User" user "User.Eco2")
		(25 "Edge.Cuts" user "Board Geometry/Outline")
		(27 "Margin" user)
		(31 "F.CrtYd" user "Package Geometry/Place Bound Top")
		(29 "B.CrtYd" user "Package Geometry/Place Bound Bottom")
		(35 "F.Fab" user "Ref Des/Assembly Top")
		(33 "B.Fab" user "Ref Des/Assembly Bottom")
	)
	(footprint ""
		(layer "B.Cu")
		(at 98.493834 -263.521952)
		(property "Reference" "C2493"
			(at 0 0 0)
			(layer "B.SilkS")
			(hide yes)
			(effects
				(font
					(size 1.27 1.27)
				)
				(justify mirror)
			)
		)
		(property "Value" ""
			(at 0 0 0)
			(layer "B.Fab")
			(effects
				(font
					(size 1.27 1.27)
				)
				(justify mirror)
			)
		)
		(duplicate_pad_numbers_are_jumpers no)
		(fp_line
			(start -0.7874 -0.4064)
			(end -0.7874 0.4064)
			(stroke
				(width 0.1524)
				(type default)
			)
			(layer "B.SilkS")
		)
		(fp_line
			(start -0.7874 0.4064)
			(end 0.7874 0.4064)
			(stroke
				(width 0.1524)
				(type default)
			)
			(layer "B.SilkS")
		)
		(fp_line
			(start 0.7874 -0.4064)
			(end -0.7874 -0.4064)
			(stroke
				(width 0.1524)
				(type default)
			)
			(layer "B.SilkS")
		)
		(fp_line
			(start 0.7874 0.4064)
			(end 0.7874 -0.4064)
			(stroke
				(width 0.1524)
				(type default)
			)
			(layer "B.SilkS")
		)
		(fp_line
			(start -0.67945 -0.3048)
			(end -0.67945 0.3048)
			(stroke
				(width 0.1)
				(type default)
			)
			(layer "B.Fab")
		)
		(fp_line
			(start -0.67945 0.3048)
			(end -0.120396 0.3048)
			(stroke
				(width 0.1)
				(type default)
			)
			(layer "B.Fab")
		)
		(fp_line
			(start -0.12065 -0.3048)
			(end -0.67945 -0.3048)
			(stroke
				(width 0.1)
				(type default)
			)
			(layer "B.Fab")
		)
		(fp_line
			(start -0.12065 -0.2794)
			(end -0.12065 -0.3048)
			(stroke
				(width 0.1)
				(type default)
			)
			(layer "B.Fab")
		)
		(fp_line
			(start -0.120396 0.2794)
			(end 0.12065 0.2794)
			(stroke
				(width 0.1)
				(type default)
			)
			(layer "B.Fab")
		)
		(fp_line
			(start -0.120396 0.3048)
			(end -0.120396 0.2794)
			(stroke
				(width 0.1)
				(type default)
			)
			(layer "B.Fab")
		)
		(fp_line
			(start 0.12065 -0.305054)
			(end 0.12065 -0.2794)
			(stroke
				(width 0.1)
				(type default)
			)
			(layer "B.Fab")
		)
		(fp_line
			(start 0.12065 -0.2794)
			(end -0.12065 -0.2794)
			(stroke
				(width 0.1)
				(type default)
			)
			(layer "B.Fab")
		)
		(fp_line
			(start 0.12065 0.2794)
			(end 0.12065 0.3048)
			(stroke
				(width 0.1)
				(type default)
			)
			(layer "B.Fab")
		)
		(fp_line
			(start 0.12065 0.3048)
			(end 0.67945 0.3048)
			(stroke
				(width 0.1)
				(type default)
			)
			(layer "B.Fab")
		)
		(fp_line
			(start 0.67945 -0.305054)
			(end 0.12065 -0.305054)
			(stroke
				(width 0.1)
				(type default)
			)
			(layer "B.Fab")
		)
		(fp_line
			(start 0.67945 0.3048)
			(end 0.67945 -0.305054)
			(stroke
				(width 0.1)
				(type default)
			)
			(layer "B.Fab")
		)
		(pad "1" smd circle
			(at 0.40005 0 180)
			(size 0 0)
			(layers "B.Cu" "B.Mask" "B.Paste")
			(net "PVDDIO_P1")
		)
		(pad "2" smd circle
			(at -0.40005 0 180)
			(size 0 0)
			(layers "B.Cu" "B.Mask" "B.Paste")
			(net "GND")
		)
	)
	(footprint ""
		(layer "B.Cu")
		(at 115.991386 -249.368564)
		(property "Reference" "C2307"
			(at 0 0 0)
			(layer "B.SilkS")
			(hide yes)
			(effects
				(font
					(size 1.27 1.27)
				)
				(justify mirror)
			)
		)
		(property "Value" ""
			(at 0 0 0)
			(layer "B.Fab")
			(effects
				(font
					(size 1.27 1.27)
				)
				(justify mirror)
			)
		)
		(duplicate_pad_numbers_are_jumpers no)
		(fp_line
			(start -0.7874 -0.4064)
			(end -0.7874 0.4064)
			(stroke
				(width 0.1524)
				(type default)
			)
			(layer "B.SilkS")
		)
		(fp_line
			(start -0.7874 0.4064)
			(end 0.7874 0.4064)
			(stroke
				(width 0.1524)
				(type default)
			)
			(layer "B.SilkS")
		)
		(fp_line
			(start 0.7874 -0.4064)
			(end -0.7874 -0.4064)
			(stroke
				(width 0.1524)
				(type default)
			)
			(layer "B.SilkS")
		)
		(fp_line
			(start 0.7874 0.4064)
			(end 0.7874 -0.4064)
			(stroke
				(width 0.1524)
				(type default)
			)
			(layer "B.SilkS")
		)
		(fp_line
			(start -0.67945 -0.3048)
			(end -0.67945 0.3048)
			(stroke
				(width 0.1)
				(type default)
			)
			(layer "B.Fab")
		)
		(fp_line
			(start -0.67945 0.3048)
			(end -0.120396 0.3048)
			(stroke
				(width 0.1)
				(type default)
			)
			(layer "B.Fab")
		)
		(fp_line
			(start -0.12065 -0.3048)
			(end -0.67945 -0.3048)
			(stroke
				(width 0.1)
				(type default)
			)
			(layer "B.Fab")
		)
		(fp_line
			(start -0.12065 -0.2794)
			(end -0.12065 -0.3048)
			(stroke
				(width 0.1)
				(type default)
			)
			(layer "B.Fab")
		)
		(fp_line
			(start -0.120396 0.2794)
			(end 0.12065 0.2794)
			(stroke
				(width 0.1)
				(type default)
			)
			(layer "B.Fab")
		)
		(fp_line
			(start -0.120396 0.3048)
			(end -0.120396 0.2794)
			(stroke
				(width 0.1)
				(type default)
			)
			(layer "B.Fab")
		)
		(fp_line
			(start 0.12065 -0.305054)
			(end 0.12065 -0.2794)
			(stroke
				(width 0.1)
				(type default)
			)
			(layer "B.Fab")
		)
		(fp_line
			(start 0.12065 -0.2794)
			(end -0.12065 -0.2794)
			(stroke
				(width 0.1)
				(type default)
			)
			(layer "B.Fab")
		)
		(fp_line
			(start 0.12065 0.2794)
			(end 0.12065 0.3048)
			(stroke
				(width 0.1)
				(type default)
			)
			(layer "B.Fab")
		)
		(fp_line
			(start 0.12065 0.3048)
			(end 0.67945 0.3048)
			(stroke
				(width 0.1)
				(type default)
			)
			(layer "B.Fab")
		)
		(fp_line
			(start 0.67945 -0.305054)
			(end 0.12065 -0.305054)
			(stroke
				(width 0.1)
				(type default)
			)
			(layer "B.Fab")
		)
		(fp_line
			(start 0.67945 0.3048)
			(end 0.67945 -0.305054)
			(stroke
				(width 0.1)
				(type default)
			)
			(layer "B.Fab")
		)
		(pad "1" smd circle
			(at 0.40005 0 180)
			(size 0 0)
			(layers "B.Cu" "B.Mask" "B.Paste")
			(net "PVDDCR_CPU0_P1")
		)
		(pad "2" smd circle
			(at -0.40005 0 180)
			(size 0 0)
			(layers "B.Cu" "B.Mask" "B.Paste")
			(net "GND")
		)
	)
)
